# S9S_MB_2U (Grand Teton) — schematic netlist excerpt (pin names and nets, part order shuffled) for the footprints in the layout excerpt that follows; sources: Cadence DE-HDL packaged netlist, KiCad conversion of 03242023_DA0F0TMBIJ0_F0T_Motherboard_J_brd_V01_OCP.brd

J29  SCONN288_ADR50017P130CC  SCONN288_ADR50017-P130CC IO  pkg DDR288S_1-1VXB  page 110
  VIN_BULK0  = P12V_S3_AUX_CPU1_NVDIMM
  RFU0  = TP_CHG_CPU1_DIMM1_FRU_0
  VIN_MGMT  = P3V3_AUX
  HSCL  = I3C_SPD_DDREFGH_CPU1_LVC1_SCL_4
  HSDA  = I3C_SPD_DDREFGH_CPU1_LVC1_SDA
  VSS0  = GND
  DQ0_A  = M_G_CPU1_SA_DQ<0>
  VSS1  = GND
  DQ1_A  = M_G_CPU1_SA_DQ<1>
  VSS2  = GND
  DQS0_A_T  = M_G_CPU1_SA_DQS_DP<0>
  DQS0_A_C  = M_G_CPU1_SA_DQS_DN<0>
  VSS3  = GND
  DQ4_A  = M_G_CPU1_SA_DQ<4>
  VSS4  = GND
  DQ5_A  = M_G_CPU1_SA_DQ<5>
  VSS5  = GND
  DQ8_A  = M_G_CPU1_SA_DQ<8>
  VSS6  = GND
  DQ9_A  = M_G_CPU1_SA_DQ<9>
  VSS7  = GND
  DQS1_A_T  = M_G_CPU1_SA_DQS_DP<1>
  DQS1_A_C  = M_G_CPU1_SA_DQS_DN<1>
  VSS8  = GND
  DQ12_A  = M_G_CPU1_SA_DQ<12>
  VSS9  = GND
  DQ13_A  = M_G_CPU1_SA_DQ<13>
  VSS10  = GND
  DQ16_A  = M_G_CPU1_SA_DQ<16>
  VSS11  = GND
  DQ17_A  = M_G_CPU1_SA_DQ<17>
  VSS12  = GND
  DQS2_A_T  = M_G_CPU1_SA_DQS_DP<2>
  DQS2_A_C  = M_G_CPU1_SA_DQS_DN<2>
  VSS13  = GND
  DQ20_A  = M_G_CPU1_SA_DQ<20>
  VSS14  = GND
  DQ21_A  = M_G_CPU1_SA_DQ<21>
  VSS15  = GND
  DQ24_A  = M_G_CPU1_SA_DQ<24>
  VSS16  = GND
  DQ25_A  = M_G_CPU1_SA_DQ<25>
  VSS17  = GND
  DQS3_A_T  = M_G_CPU1_SA_DQS_DP<3>
  DQS3_A_C  = M_G_CPU1_SA_DQS_DN<3>
  VSS18  = GND
  DQ28_A  = M_G_CPU1_SA_DQ<28>
  VSS19  = GND
  DQ29_A  = M_G_CPU1_SA_DQ<29>
  VSS20  = GND
  CB0_A  = M_G_CPU1_SA_CB<0>
  VSS21  = GND
  CB1_A  = M_G_CPU1_SA_CB<1>
  VSS22  = GND
  DQS4_A_T  = M_G_CPU1_SA_DQS_DP<4>
  DQS4_A_C  = M_G_CPU1_SA_DQS_DN<4>
  VSS23  = GND
  CB4_A  = M_G_CPU1_SA_CB<4>
  VSS24  = GND
  CB5_A  = M_G_CPU1_SA_CB<5>
  VSS25  = GND
  ALERT_N  = M_G_CPU1_ALERT_N
  VSS26  = GND
  CS0_A_N  = M_G_CPU1_SA_CS_N<0>
  VSS27  = GND
  CA0_A  = M_G_CPU1_SA_CA<0>
  VSS28  = GND
  CA2_A  = M_G_CPU1_SA_CA<2>
  VSS29  = GND
  CA4_A  = M_G_CPU1_SA_CA<4>
  VSS30  = GND
  CA6_A  = M_G_CPU1_SA_CA<6>
  VSS31  = GND
  PAR_A  = M_G_CPU1_SA_PAR
  VSS32  = GND
  CA0_B  = M_G_CPU1_SB_CA<0>
  VSS33  = GND
  CA2_B  = M_G_CPU1_SB_CA<2>
  VSS34  = GND
  CA4_B  = M_G_CPU1_SB_CA<4>
  VSS35  = GND
  CA6_B  = M_G_CPU1_SB_CA<6>
  VSS36  = GND
  CS0_B_N  = M_G_CPU1_SB_CS_N<0>
  VSS37  = GND
  \lbd||rsp_a_n\  = M_G_CPU1_SA_RSP<0>
  \lbs||rsp_b_n\  = M_G_CPU1_SB_RSP<0>
  VSS38  = GND
  CB4_B  = M_G_CPU1_SB_CB<4>
  VSS39  = GND
  CB5_B  = M_G_CPU1_SB_CB<5>
  VSS40  = GND
  \dqs9_b_t||tdqs9_b_t||dbi4_b_n\  = M_G_CPU1_SB_DQS_DP<9>
  \dqs9_b_c||tdqs9_b_c\  = M_G_CPU1_SB_DQS_DN<9>
  VSS41  = GND
  CB0_B  = M_G_CPU1_SB_CB<0>
  VSS42  = GND
  CB1_B  = M_G_CPU1_SB_CB<1>
  VSS43  = GND
  DQ0_B  = M_G_CPU1_SB_DQ<0>
  VSS44  = GND
  DQ1_B  = M_G_CPU1_SB_DQ<1>
  VSS45  = GND
  DQS0_B_T  = M_G_CPU1_SB_DQS_DP<0>
  DQS0_B_C  = M_G_CPU1_SB_DQS_DN<0>
  VSS46  = GND
  DQ4_B  = M_G_CPU1_SB_DQ<4>
  VSS47  = GND
  DQ5_B  = M_G_CPU1_SB_DQ<5>
  VSS48  = GND
  DQ8_B  = M_G_CPU1_SB_DQ<8>
  VSS49  = GND
  DQ9_B  = M_G_CPU1_SB_DQ<9>
  VSS50  = GND
  DQS1_B_T  = M_G_CPU1_SB_DQS_DP<1>
  DQS1_B_C  = M_G_CPU1_SB_DQS_DN<1>
  VSS51  = GND
  DQ12_B  = M_G_CPU1_SB_DQ<12>
  VSS52  = GND
  DQ13_B  = M_G_CPU1_SB_DQ<13>
  VSS53  = GND
  DQ16_B  = M_G_CPU1_SB_DQ<16>
  VSS54  = GND
  DQ17_B  = M_G_CPU1_SB_DQ<17>
  VSS55  = GND
  DQS2_B_T  = M_G_CPU1_SB_DQS_DP<2>
  DQS2_B_C  = M_G_CPU1_SB_DQS_DN<2>
  VSS56  = GND
  DQ20_B  = M_G_CPU1_SB_DQ<20>
  VSS57  = GND
  DQ21_B  = M_G_CPU1_SB_DQ<21>
  VSS58  = GND
  DQ24_B  = M_G_CPU1_SB_DQ<24>
  VSS59  = GND
  DQ25_B  = M_G_CPU1_SB_DQ<25>
  VSS60  = GND
  DQS3_B_T  = M_G_CPU1_SB_DQS_DP<3>
  DQS3_B_C  = M_G_CPU1_SB_DQS_DN<3>
  VSS61  = GND
  DQ28_B  = M_G_CPU1_SB_DQ<28>
  VSS62  = GND
  DQ29_B  = M_G_CPU1_SB_DQ<29>
  VSS63  = GND
  RFU1  = TP_CHG_CPU1_DIMM1_FRU_1
  VIN_BULK1  = P12V_S3_AUX_CPU1_NVDIMM
  VIN_BULK2  = P12V_S3_AUX_CPU1_NVDIMM
  \pwr_good||fail_n\  = PWRGD_CHG_CPU1_DIMM1
  HSA  = PD_CHG_CPU1_DIMM1_SAA
  RFU2  = TP_CHG_CPU1_DIMM1_FRU_2
  RFU3  = TP_CHG_CPU1_DIMM1_FRU_3
  VSS64  = GND
  DQ2_A  = M_G_CPU1_SA_DQ<2>
  VSS65  = GND
  DQ3_A  = M_G_CPU1_SA_DQ<3>
  VSS66  = GND
  \dqs5_a_c||tdqs5_a_c||dqs5_a_t||tdqs5_a_t\  = M_G_CPU1_SA_DQS_DN<5>
  \dqs5_a_t||tdqs5_a_t\  = M_G_CPU1_SA_DQS_DP<5>
  VSS67  = GND
  DQ6_A  = M_G_CPU1_SA_DQ<6>
  VSS68  = GND
  DQ7_A  = M_G_CPU1_SA_DQ<7>
  VSS69  = GND
  DQ10_A  = M_G_CPU1_SA_DQ<10>
  VSS70  = GND
  DQ11_A  = M_G_CPU1_SA_DQ<11>
  VSS71  = GND
  \dqs6_a_c||tdqs6_a_c||dqs6_a_t||tdqs6_a_t\  = M_G_CPU1_SA_DQS_DN<6>
  \dqs6_a_t||tdqs6_a_t\  = M_G_CPU1_SA_DQS_DP<6>
  VSS72  = GND
  DQ14_A  = M_G_CPU1_SA_DQ<14>
  VSS73  = GND
  DQ15_A  = M_G_CPU1_SA_DQ<15>
  VSS74  = GND
  DQ18_A  = M_G_CPU1_SA_DQ<18>
  VSS75  = GND
  DQ19_A  = M_G_CPU1_SA_DQ<19>
  VSS76  = GND
  \dqs7_a_c||tdqs7_a_c\  = M_G_CPU1_SA_DQS_DN<7>
  \dqs7_a_t||tdqs7_a_t\  = M_G_CPU1_SA_DQS_DP<7>
  VSS77  = GND
  DQ22_A  = M_G_CPU1_SA_DQ<22>
  VSS78  = GND
  DQ23_A  = M_G_CPU1_SA_DQ<23>
  VSS79  = GND
  DQ26_A  = M_G_CPU1_SA_DQ<26>
  VSS80  = GND
  DQ27_A  = M_G_CPU1_SA_DQ<27>
  VSS81  = GND
  \dqs8_a_c||tdqs8_a_c\  = M_G_CPU1_SA_DQS_DN<8>
  \dqs8_a_t||tdqs8_a_t\  = M_G_CPU1_SA_DQS_DP<8>
  VSS82  = GND
  DQ30_A  = M_G_CPU1_SA_DQ<30>
  VSS83  = GND
  DQ31_A  = M_G_CPU1_SA_DQ<31>
  VSS84  = GND
  CB2_A  = M_G_CPU1_SA_CB<2>
  VSS85  = GND
  CB3_A  = M_G_CPU1_SA_CB<3>
  VSS86  = GND
  \dqs9_a_c||tdqs9_a_c\  = M_G_CPU1_SA_DQS_DN<9>
  \dqs9_a_t||tdqs9_a_t\  = M_G_CPU1_SA_DQS_DP<9>
  VSS87  = GND
  CB6_A  = M_G_CPU1_SA_CB<6>
  VSS88  = GND
  CB7_A  = M_G_CPU1_SA_CB<7>
  VSS89  = GND
  RESET_N  = RST_M_GH_CPU1_FPGA_N
  VSS90  = GND
  CS1_A_N  = M_G_CPU1_SA_CS_N<1>
  VSS91  = GND
  CA1_A  = M_G_CPU1_SA_CA<1>
  VSS92  = GND
  CA3_A  = M_G_CPU1_SA_CA<3>
  VSS93  = GND
  CA5_A  = M_G_CPU1_SA_CA<5>
  VSS94  = GND
  CK_T  = M_G_CPU1_CLK_DP<0>
  CK_C  = M_G_CPU1_CLK_DN<0>
  VSS95  = GND
  RFU4  = TP_CHG_CPU1_DIMM1_FRU_4
  CA1_B  = M_G_CPU1_SB_CA<1>
  VSS96  = GND
  CA3_B  = M_G_CPU1_SB_CA<3>
  VSS97  = GND
  CA5_B  = M_G_CPU1_SB_CA<5>
  VSS98  = GND
  PAR_B  = M_G_CPU1_SB_PAR
  VSS99  = GND
  CS1_B_N  = M_G_CPU1_SB_CS_N<1>
  VSS100  = GND
  RFU5  = TP_CHG_CPU1_DIMM1_FRU_5
  RFU6  = TP_CHG_CPU1_DIMM1_FRU_6
  VSS101  = GND
  CB6_B  = M_G_CPU1_SB_CB<6>
  VSS102  = GND
  CB7_B  = M_G_CPU1_SB_CB<7>
  VSS103  = GND
  DQS4_B_C  = M_G_CPU1_SB_DQS_DN<4>
  DQS4_B_T  = M_G_CPU1_SB_DQS_DP<4>
  VSS104  = GND
  CB2_B  = M_G_CPU1_SB_CB<2>
  VSS105  = GND
  CB3_B  = M_G_CPU1_SB_CB<3>
  VSS106  = GND
  DQ2_B  = M_G_CPU1_SB_DQ<2>
  VSS107  = GND
  DQ3_B  = M_G_CPU1_SB_DQ<3>
  VSS108  = GND
  \dqs5_b_c||tdqs5_b_c\  = M_G_CPU1_SB_DQS_DN<5>
  \dqs5_b_t||tdqs5_b_t\  = M_G_CPU1_SB_DQS_DP<5>
  VSS109  = GND
  DQ6_B  = M_G_CPU1_SB_DQ<6>
  VSS110  = GND
  DQ7_B  = M_G_CPU1_SB_DQ<7>
  VSS111  = GND
  DQ10_B  = M_G_CPU1_SB_DQ<10>
  VSS112  = GND
  DQ11_B  = M_G_CPU1_SB_DQ<11>
  VSS113  = GND
  \dqs6_b_c||tdqs6_b_c\  = M_G_CPU1_SB_DQS_DN<6>
  \dqs6_b_t||tdqs6_b_t\  = M_G_CPU1_SB_DQS_DP<6>
  VSS114  = GND
  DQ14_B  = M_G_CPU1_SB_DQ<14>
  VSS115  = GND
  DQ15_B  = M_G_CPU1_SB_DQ<15>
  VSS116  = GND
  DQ18_B  = M_G_CPU1_SB_DQ<18>
  VSS117  = GND
  DQ19_B  = M_G_CPU1_SB_DQ<19>
  VSS118  = GND
  \dqs7_b_c||tdqs7_b_c\  = M_G_CPU1_SB_DQS_DN<7>
  \dqs7_b_t||tdqs7_b_t\  = M_G_CPU1_SB_DQS_DP<7>
  VSS119  = GND
  DQ22_B  = M_G_CPU1_SB_DQ<22>
  VSS120  = GND
  DQ23_B  = M_G_CPU1_SB_DQ<23>
  VSS121  = GND
  DQ26_B  = M_G_CPU1_SB_DQ<26>
  VSS122  = GND
  DQ27_B  = M_G_CPU1_SB_DQ<27>
  VSS123  = GND
  \dqs8_b_c||tdqs8_b_c\  = M_G_CPU1_SB_DQS_DN<8>
  \dqs8_b_t||tdqs8_b_t\  = M_G_CPU1_SB_DQS_DP<8>
  VSS124  = GND
  DQ30_B  = M_G_CPU1_SB_DQ<30>
  VSS125  = GND
  DQ31_B  = M_G_CPU1_SB_DQ<31>
  VSS126  = GND
  G1  = GND
  G2  = GND
  G3  = GND

(kicad_pcb
	(version 20260206)
	(generator "pcbnew")
	(generator_version "10.0")
	(general
		(thickness 1.6)
		(legacy_teardrops no)
	)
	(paper "A4")
	(title_block
		(title "03242023_DA0F0TMBIJ0_F0T_Motherboard_J_brd_V01_OCP.brd")
		(comment 1 "Grand Teton / footprint 2874 of 6105 (J29), pads 183-228 of 291")
	)
	(layers
		(0 "F.Cu" signal "TOP")
		(4 "In1.Cu" signal "GND")
		(6 "In2.Cu" signal "IN1")
		(8 "In3.Cu" signal "GND1")
		(10 "In4.Cu" signal "IN2")
		(12 "In5.Cu" signal "GND2")
		(14 "In6.Cu" signal "IN3")
		(16 "In7.Cu" signal "GND3")
		(18 "In8.Cu" signal "VCC")
		(20 "In9.Cu" signal "VCC1")
		(22 "In10.Cu" signal "GND4")
		(24 "In11.Cu" signal "IN4")
		(26 "In12.Cu" signal "GND5")
		(28 "In13.Cu" signal "IN5")
		(30 "In14.Cu" signal "GND6")
		(32 "In15.Cu" signal "IN6")
		(34 "In16.Cu" signal "GND7")
		(2 "B.Cu" signal "BOTTOM")
		(9 "F.Adhes" user "F.Adhesive")
		(11 "B.Adhes" user "B.Adhesive")
		(13 "F.Paste" user "Package Geometry/Pastemask Top")
		(15 "B.Paste" user "Package Geometry/Pastemask Bottom")
		(5 "F.SilkS" user "Ref Des/Silkscreen Top")
		(7 "B.SilkS" user "Ref Des/Silkscreen Bottom")
		(1 "F.Mask" user "Board Geometry/Soldermask Top")
		(3 "B.Mask" user "Board Geometry/Soldermask Bottom")
		(17 "Dwgs.User" user "User.Drawings")
		(19 "Cmts.User" user "User.Comments")
		(21 "Eco1.User" user "User.Eco1")
		(23 "Eco2.User" user "User.Eco2")
		(25 "Edge.Cuts" user "Board Geometry/Outline")
		(27 "Margin" user)
		(31 "F.CrtYd" user "Package Geometry/Place Bound Top")
		(29 "B.CrtYd" user "Package Geometry/Place Bound Bottom")
		(35 "F.Fab" user "Ref Des/Assembly Top")
		(33 "B.Fab" user "Ref Des/Assembly Bottom")
	)
	(footprint ""
		(layer "F.Cu")
		(at 198.58228 -258.091686)
		(property "Reference" "J29"
			(at -3.683 -81.702148 0)
			(unlocked yes)
			(layer "F.SilkS")
			(effects
				(font
					(size 0.7874 0.5842)
					(thickness 0.1524)
				)
				(justify left)
			)
		)
		(property "Value" ""
			(at 0 0 0)
			(layer "F.Fab")
			(effects
				(font
					(size 1.27 1.27)
				)
			)
		)
		(duplicate_pad_numbers_are_jumpers no)
		(pad "183" smd rect
			(at 2.050034 -31.025084 270)
			(size 0.519938 1.4986)
			(layers "F.Cu" "F.Mask" "F.Paste")
			(net "M_G_CPU1_SA_DQ<23>")
		)
		(pad "184" smd rect
			(at 2.050034 -30.174946 270)
			(size 0.519938 1.4986)
			(layers "F.Cu" "F.Mask" "F.Paste")
			(net "GND")
		)
		(pad "185" smd rect
			(at 2.050034 -29.325062 270)
			(size 0.519938 1.4986)
			(layers "F.Cu" "F.Mask" "F.Paste")
			(net "M_G_CPU1_SA_DQ<26>")
		)
		(pad "186" smd rect
			(at 2.050034 -28.474924 270)
			(size 0.519938 1.4986)
			(layers "F.Cu" "F.Mask" "F.Paste")
			(net "GND")
		)
		(pad "187" smd rect
			(at 2.050034 -27.62504 270)
			(size 0.519938 1.4986)
			(layers "F.Cu" "F.Mask" "F.Paste")
			(net "M_G_CPU1_SA_DQ<27>")
		)
		(pad "188" smd rect
			(at 2.050034 -26.774902 270)
			(size 0.519938 1.4986)
			(layers "F.Cu" "F.Mask" "F.Paste")
			(net "GND")
		)
		(pad "189" smd rect
			(at 2.050034 -25.925018 270)
			(size 0.519938 1.4986)
			(layers "F.Cu" "F.Mask" "F.Paste")
			(net "M_G_CPU1_SA_DQS_DN<8>")
		)
		(pad "190" smd rect
			(at 2.050034 -25.07488 270)
			(size 0.519938 1.4986)
			(layers "F.Cu" "F.Mask" "F.Paste")
			(net "M_G_CPU1_SA_DQS_DP<8>")
		)
		(pad "191" smd rect
			(at 2.050034 -24.224996 270)
			(size 0.519938 1.4986)
			(layers "F.Cu" "F.Mask" "F.Paste")
			(net "GND")
		)
		(pad "192" smd rect
			(at 2.050034 -23.375112 270)
			(size 0.519938 1.4986)
			(layers "F.Cu" "F.Mask" "F.Paste")
			(net "M_G_CPU1_SA_DQ<30>")
		)
		(pad "193" smd rect
			(at 2.050034 -22.524974 270)
			(size 0.519938 1.4986)
			(layers "F.Cu" "F.Mask" "F.Paste")
			(net "GND")
		)
		(pad "194" smd rect
			(at 2.050034 -21.67509 270)
			(size 0.519938 1.4986)
			(layers "F.Cu" "F.Mask" "F.Paste")
			(net "M_G_CPU1_SA_DQ<31>")
		)
		(pad "195" smd rect
			(at 2.050034 -20.824952 270)
			(size 0.519938 1.4986)
			(layers "F.Cu" "F.Mask" "F.Paste")
			(net "GND")
		)
		(pad "196" smd rect
			(at 2.050034 -19.975068 270)
			(size 0.519938 1.4986)
			(layers "F.Cu" "F.Mask" "F.Paste")
			(net "M_G_CPU1_SA_CB<2>")
		)
		(pad "197" smd rect
			(at 2.050034 -19.12493 270)
			(size 0.519938 1.4986)
			(layers "F.Cu" "F.Mask" "F.Paste")
			(net "GND")
		)
		(pad "198" smd rect
			(at 2.050034 -18.275046 270)
			(size 0.519938 1.4986)
			(layers "F.Cu" "F.Mask" "F.Paste")
			(net "M_G_CPU1_SA_CB<3>")
		)
		(pad "199" smd rect
			(at 2.050034 -17.424908 270)
			(size 0.519938 1.4986)
			(layers "F.Cu" "F.Mask" "F.Paste")
			(net "GND")
		)
		(pad "200" smd rect
			(at 2.050034 -16.575024 270)
			(size 0.519938 1.4986)
			(layers "F.Cu" "F.Mask" "F.Paste")
			(net "M_G_CPU1_SA_DQS_DN<9>")
		)
		(pad "201" smd rect
			(at 2.050034 -15.724886 270)
			(size 0.519938 1.4986)
			(layers "F.Cu" "F.Mask" "F.Paste")
			(net "M_G_CPU1_SA_DQS_DP<9>")
		)
		(pad "202" smd rect
			(at 2.050034 -14.875002 270)
			(size 0.519938 1.4986)
			(layers "F.Cu" "F.Mask" "F.Paste")
			(net "GND")
		)
		(pad "203" smd rect
			(at 2.050034 -14.025118 270)
			(size 0.519938 1.4986)
			(layers "F.Cu" "F.Mask" "F.Paste")
			(net "M_G_CPU1_SA_CB<6>")
		)
		(pad "204" smd rect
			(at 2.050034 -13.17498 270)
			(size 0.519938 1.4986)
			(layers "F.Cu" "F.Mask" "F.Paste")
			(net "GND")
		)
		(pad "205" smd rect
			(at 2.050034 -12.325096 270)
			(size 0.519938 1.4986)
			(layers "F.Cu" "F.Mask" "F.Paste")
			(net "M_G_CPU1_SA_CB<7>")
		)
		(pad "206" smd rect
			(at 2.050034 -11.474958 270)
			(size 0.519938 1.4986)
			(layers "F.Cu" "F.Mask" "F.Paste")
			(net "GND")
		)
		(pad "207" smd rect
			(at 2.050034 -10.625074 270)
			(size 0.519938 1.4986)
			(layers "F.Cu" "F.Mask" "F.Paste")
			(net "RST_M_GH_CPU1_FPGA_N")
		)
		(pad "208" smd rect
			(at 2.050034 -9.774936 270)
			(size 0.519938 1.4986)
			(layers "F.Cu" "F.Mask" "F.Paste")
			(net "GND")
		)
		(pad "209" smd rect
			(at 2.050034 -8.925052 270)
			(size 0.519938 1.4986)
			(layers "F.Cu" "F.Mask" "F.Paste")
			(net "M_G_CPU1_SA_CS_N<1>")
		)
		(pad "210" smd rect
			(at 2.050034 -8.074914 270)
			(size 0.519938 1.4986)
			(layers "F.Cu" "F.Mask" "F.Paste")
			(net "GND")
		)
		(pad "211" smd rect
			(at 2.050034 -7.22503 270)
			(size 0.519938 1.4986)
			(layers "F.Cu" "F.Mask" "F.Paste")
			(net "M_G_CPU1_SA_CA<1>")
		)
		(pad "212" smd rect
			(at 2.050034 -6.374892 270)
			(size 0.519938 1.4986)
			(layers "F.Cu" "F.Mask" "F.Paste")
			(net "GND")
		)
		(pad "213" smd rect
			(at 2.050034 -5.525008 270)
			(size 0.519938 1.4986)
			(layers "F.Cu" "F.Mask" "F.Paste")
			(net "M_G_CPU1_SA_CA<3>")
		)
		(pad "214" smd rect
			(at 2.050034 -4.675124 270)
			(size 0.519938 1.4986)
			(layers "F.Cu" "F.Mask" "F.Paste")
			(net "GND")
		)
		(pad "215" smd rect
			(at 2.050034 -3.824986 270)
			(size 0.519938 1.4986)
			(layers "F.Cu" "F.Mask" "F.Paste")
			(net "M_G_CPU1_SA_CA<5>")
		)
		(pad "216" smd rect
			(at 2.050034 -2.975102 270)
			(size 0.519938 1.4986)
			(layers "F.Cu" "F.Mask" "F.Paste")
			(net "GND")
		)
		(pad "217" smd rect
			(at 2.050034 -2.124964 270)
			(size 0.519938 1.4986)
			(layers "F.Cu" "F.Mask" "F.Paste")
			(net "M_G_CPU1_CLK_DP<0>")
		)
		(pad "218" smd rect
			(at 2.050034 -1.27508 270)
			(size 0.519938 1.4986)
			(layers "F.Cu" "F.Mask" "F.Paste")
			(net "M_G_CPU1_CLK_DN<0>")
		)
		(pad "219" smd rect
			(at 2.050034 -0.424942 270)
			(size 0.519938 1.4986)
			(layers "F.Cu" "F.Mask" "F.Paste")
			(net "GND")
		)
		(pad "220" smd rect
			(at 2.050034 5.525008 270)
			(size 0.519938 1.4986)
			(layers "F.Cu" "F.Mask" "F.Paste")
			(net "TP_CHG_CPU1_DIMM1_FRU_4")
		)
		(pad "221" smd rect
			(at 2.050034 6.374892 270)
			(size 0.519938 1.4986)
			(layers "F.Cu" "F.Mask" "F.Paste")
			(net "M_G_CPU1_SB_CA<1>")
		)
		(pad "222" smd rect
			(at 2.050034 7.22503 270)
			(size 0.519938 1.4986)
			(layers "F.Cu" "F.Mask" "F.Paste")
			(net "GND")
		)
		(pad "223" smd rect
			(at 2.050034 8.074914 270)
			(size 0.519938 1.4986)
			(layers "F.Cu" "F.Mask" "F.Paste")
			(net "M_G_CPU1_SB_CA<3>")
		)
		(pad "224" smd rect
			(at 2.050034 8.925052 270)
			(size 0.519938 1.4986)
			(layers "F.Cu" "F.Mask" "F.Paste")
			(net "GND")
		)
		(pad "225" smd rect
			(at 2.050034 9.774936 270)
			(size 0.519938 1.4986)
			(layers "F.Cu" "F.Mask" "F.Paste")
			(net "M_G_CPU1_SB_CA<5>")
		)
		(pad "226" smd rect
			(at 2.050034 10.625074 270)
			(size 0.519938 1.4986)
			(layers "F.Cu" "F.Mask" "F.Paste")
			(net "GND")
		)
		(pad "227" smd rect
			(at 2.050034 11.474958 270)
			(size 0.519938 1.4986)
			(layers "F.Cu" "F.Mask" "F.Paste")
			(net "M_G_CPU1_SB_PAR")
		)
		(pad "228" smd rect
			(at 2.050034 12.325096 270)
			(size 0.519938 1.4986)
			(layers "F.Cu" "F.Mask" "F.Paste")
			(net "GND")
		)
	)
)
